(kicad_pcb
	(version 20260206)
	(generator "pcbnew")
	(generator_version "10.0")
	(general
		(thickness 1.6)
		(legacy_teardrops no)
	)
	(paper "A4")
	(title_block
		(title "Bryce Canyon_F.DPB_16315-1-OCP.brd")
		(comment 1 "Bryce Canyon / footprints 1586-1592 of 2223")
	)
	(layers
		(0 "F.Cu" signal "TOP")
		(4 "In1.Cu" signal "L2GND")
		(6 "In2.Cu" signal "L3")
		(8 "In3.Cu" signal "L4GND")
		(10 "In4.Cu" signal "L5")
		(12 "In5.Cu" signal "L6VCC")
		(14 "In6.Cu" signal "L7VCC")
		(16 "In7.Cu" signal "L8")
		(18 "In8.Cu" signal "L9GND")
		(20 "In9.Cu" signal "L10")
		(22 "In10.Cu" signal "L11GND")
		(2 "B.Cu" signal "BOTTOM")
		(9 "F.Adhes" user "F.Adhesive")
		(11 "B.Adhes" user "B.Adhesive")
		(13 "F.Paste" user "Package Geometry/Pastemask Top")
		(15 "B.Paste" user "Package Geometry/Pastemask Bottom")
		(5 "F.SilkS" user "Ref Des/Silkscreen Top")
		(7 "B.SilkS" user "Ref Des/Silkscreen Bottom")
		(1 "F.Mask" user "Board Geometry/Soldermask Top")
		(3 "B.Mask" user "Board Geometry/Soldermask Bottom")
		(17 "Dwgs.User" user "User.Drawings")
		(19 "Cmts.User" user "User.Comments")
		(21 "Eco1.User" user "User.Eco1")
		(23 "Eco2.User" user "User.Eco2")
		(25 "Edge.Cuts" user "Board Geometry/Outline")
		(27 "Margin" user)
		(31 "F.CrtYd" user "Package Geometry/Place Bound Top")
		(29 "B.CrtYd" user "Package Geometry/Place Bound Bottom")
		(35 "F.Fab" user "Ref Des/Assembly Top")
		(33 "B.Fab" user "Ref Des/Assembly Bottom")
	)
	(footprint ""
		(layer "F.Cu")
		(at 227.66909 -387.783832)
		(property "Reference" "R1107"
			(at 0 0 0)
			(layer "F.SilkS")
			(hide yes)
			(effects
				(font
					(size 1.27 1.27)
				)
			)
		)
		(property "Value" "10KR2F-2-GP"
			(at 0.064008 -3.993896 0)
			(unlocked yes)
			(layer "F.Fab")
			(hide yes)
			(effects
				(font
					(size 1.016 1.016)
					(thickness 0.1524)
				)
			)
		)
		(property "Device Type" "R402H16"
			(at 0.064008 -5.517896 0)
			(unlocked yes)
			(layer "F.Fab")
			(hide yes)
			(effects
				(font
					(size 1.016 1.016)
					(thickness 0.1524)
				)
			)
		)
		(duplicate_pad_numbers_are_jumpers no)
		(fp_line
			(start -0.508 -0.9398)
			(end -0.508 0.9398)
			(stroke
				(width 0.1524)
				(type default)
			)
			(layer "F.SilkS")
		)
		(fp_line
			(start 0.508 -0.9398)
			(end -0.508 -0.9398)
			(stroke
				(width 0.1524)
				(type default)
			)
			(layer "F.SilkS")
		)
		(fp_rect
			(start -0.508 0.9398)
			(end 0.508 -0.9398)
			(stroke
				(width 0)
				(type default)
			)
			(fill no)
			(layer "F.CrtYd")
		)
		(fp_rect
			(start -0.508 0.9398)
			(end 0.508 -0.9398)
			(stroke
				(width 0)
				(type default)
			)
			(fill no)
			(layer "F.Fab")
		)
		(pad "1" smd custom
			(at 0 -0.4445)
			(size 0.1397 0.1397)
			(layers "F.Cu" "F.Mask" "F.Paste")
			(net "P12V_IN")
			(options
				(clearance outline)
				(anchor circle)
			)
			(primitives
				(gr_poly
					(pts
						(arc
							(start -0.1778 -0.2794)
							(mid -0.249642 -0.249642)
							(end -0.2794 -0.1778)
						)
						(arc
							(start -0.2794 0.1778)
							(mid -0.249642 0.249642)
							(end -0.1778 0.2794)
						)
						(arc
							(start 0.1778 0.2794)
							(mid 0.249642 0.249642)
							(end 0.2794 0.1778)
						)
						(arc
							(start 0.2794 -0.1778)
							(mid 0.249642 -0.249642)
							(end 0.1778 -0.2794)
						)
					)
					(width 0)
					(fill yes)
				)
			)
		)
		(pad "2" smd custom
			(at 0 0.4445)
			(size 0.1397 0.1397)
			(layers "F.Cu" "F.Mask" "F.Paste")
			(net "DPB_PWR_BTN_BUF_A")
			(options
				(clearance outline)
				(anchor circle)
			)
			(primitives
				(gr_poly
					(pts
						(arc
							(start -0.1778 -0.2794)
							(mid -0.249642 -0.249642)
							(end -0.2794 -0.1778)
						)
						(arc
							(start -0.2794 0.1778)
							(mid -0.249642 0.249642)
							(end -0.1778 0.2794)
						)
						(arc
							(start 0.1778 0.2794)
							(mid 0.249642 0.249642)
							(end 0.2794 0.1778)
						)
						(arc
							(start 0.2794 -0.1778)
							(mid 0.249642 -0.249642)
							(end 0.1778 -0.2794)
						)
					)
					(width 0)
					(fill yes)
				)
			)
		)
	)
	(footprint ""
		(layer "F.Cu")
		(at 16.824198 -283.152342 -90)
		(property "Reference" "C516"
			(at 0 0 270)
			(layer "F.SilkS")
			(hide yes)
			(effects
				(font
					(size 1.27 1.27)
				)
			)
		)
		(property "Value" "SCD033U25V2KX-GP"
			(at 1.1811 -2.7051 270)
			(unlocked yes)
			(layer "F.Fab")
			(hide yes)
			(effects
				(font
					(size 1.016 1.016)
					(thickness 0.1524)
				)
			)
		)
		(property "Device Type" "C402H22"
			(at 1.1811 -4.2291 270)
			(unlocked yes)
			(layer "F.Fab")
			(hide yes)
			(effects
				(font
					(size 1.016 1.016)
					(thickness 0.1524)
				)
			)
		)
		(duplicate_pad_numbers_are_jumpers no)
		(fp_rect
			(start -0.4318 0.9525)
			(end 0.4318 -0.9525)
			(stroke
				(width 0)
				(type default)
			)
			(fill no)
			(layer "F.CrtYd")
		)
		(fp_rect
			(start -0.4318 0.9525)
			(end 0.4318 -0.9525)
			(stroke
				(width 0)
				(type default)
			)
			(fill no)
			(layer "F.Fab")
		)
		(pad "1" smd custom
			(at 0 -0.4445 270)
			(size 0.1524 0.1524)
			(layers "F.Cu" "F.Mask" "F.Paste")
			(net "SW_HDD_P0")
			(options
				(clearance outline)
				(anchor circle)
			)
			(primitives
				(gr_poly
					(pts
						(arc
							(start 0.3048 -0.2032)
							(mid 0.275042 -0.275042)
							(end 0.2032 -0.3048)
						)
						(arc
							(start -0.2032 -0.3048)
							(mid -0.275042 -0.275042)
							(end -0.3048 -0.2032)
						)
						(arc
							(start -0.3048 0.2032)
							(mid -0.275042 0.275042)
							(end -0.2032 0.3048)
						)
						(arc
							(start 0.2032 0.3048)
							(mid 0.275042 0.275042)
							(end 0.3048 0.2032)
						)
					)
					(width 0)
					(fill yes)
				)
			)
		)
		(pad "2" smd custom
			(at 0 0.4445 270)
			(size 0.1524 0.1524)
			(layers "F.Cu" "F.Mask" "F.Paste")
			(net "GND")
			(options
				(clearance outline)
				(anchor circle)
			)
			(primitives
				(gr_poly
					(pts
						(arc
							(start 0.3048 -0.2032)
							(mid 0.275042 -0.275042)
							(end 0.2032 -0.3048)
						)
						(arc
							(start -0.2032 -0.3048)
							(mid -0.275042 -0.275042)
							(end -0.3048 -0.2032)
						)
						(arc
							(start -0.3048 0.2032)
							(mid -0.275042 0.275042)
							(end -0.2032 0.3048)
						)
						(arc
							(start 0.2032 0.3048)
							(mid 0.275042 0.275042)
							(end 0.3048 0.2032)
						)
					)
					(width 0)
					(fill yes)
				)
			)
		)
	)
	(footprint ""
		(layer "F.Cu")
		(at 402.782278 -32.513016)
		(property "Reference" "R12"
			(at 0 0 0)
			(layer "F.SilkS")
			(hide yes)
			(effects
				(font
					(size 1.27 1.27)
				)
			)
		)
		(property "Value" "0R2J-2-GP"
			(at 0.064008 -3.993896 0)
			(unlocked yes)
			(layer "F.Fab")
			(hide yes)
			(effects
				(font
					(size 1.016 1.016)
					(thickness 0.1524)
				)
			)
		)
		(property "Device Type" "R402H16"
			(at 0.064008 -5.517896 0)
			(unlocked yes)
			(layer "F.Fab")
			(hide yes)
			(effects
				(font
					(size 1.016 1.016)
					(thickness 0.1524)
				)
			)
		)
		(duplicate_pad_numbers_are_jumpers no)
		(fp_line
			(start -0.508 -0.9398)
			(end -0.508 0.9398)
			(stroke
				(width 0.1524)
				(type default)
			)
			(layer "F.SilkS")
		)
		(fp_line
			(start 0.508 -0.9398)
			(end -0.508 -0.9398)
			(stroke
				(width 0.1524)
				(type default)
			)
			(layer "F.SilkS")
		)
		(fp_rect
			(start -0.508 0.9398)
			(end 0.508 -0.9398)
			(stroke
				(width 0)
				(type default)
			)
			(fill no)
			(layer "F.CrtYd")
		)
		(fp_rect
			(start -0.508 0.9398)
			(end 0.508 -0.9398)
			(stroke
				(width 0)
				(type default)
			)
			(fill no)
			(layer "F.Fab")
		)
		(pad "1" smd custom
			(at 0 -0.4445)
			(size 0.1397 0.1397)
			(layers "F.Cu" "F.Mask" "F.Paste")
			(net "GND")
			(options
				(clearance outline)
				(anchor circle)
			)
			(primitives
				(gr_poly
					(pts
						(arc
							(start -0.1778 -0.2794)
							(mid -0.249642 -0.249642)
							(end -0.2794 -0.1778)
						)
						(arc
							(start -0.2794 0.1778)
							(mid -0.249642 0.249642)
							(end -0.1778 0.2794)
						)
						(arc
							(start 0.1778 0.2794)
							(mid 0.249642 0.249642)
							(end 0.2794 0.1778)
						)
						(arc
							(start 0.2794 -0.1778)
							(mid 0.249642 -0.249642)
							(end 0.1778 -0.2794)
						)
					)
					(width 0)
					(fill yes)
				)
			)
		)
		(pad "2" smd custom
			(at 0 0.4445)
			(size 0.1397 0.1397)
			(layers "F.Cu" "F.Mask" "F.Paste")
			(net "IOM_B_MATED_N")
			(options
				(clearance outline)
				(anchor circle)
			)
			(primitives
				(gr_poly
					(pts
						(arc
							(start -0.1778 -0.2794)
							(mid -0.249642 -0.249642)
							(end -0.2794 -0.1778)
						)
						(arc
							(start -0.2794 0.1778)
							(mid -0.249642 0.249642)
							(end -0.1778 0.2794)
						)
						(arc
							(start 0.1778 0.2794)
							(mid 0.249642 0.249642)
							(end 0.2794 0.1778)
						)
						(arc
							(start 0.2794 -0.1778)
							(mid 0.249642 -0.249642)
							(end 0.1778 -0.2794)
						)
					)
					(width 0)
					(fill yes)
				)
			)
		)
	)
	(footprint ""
		(layer "F.Cu")
		(at 77.892148 -275.633942 90)
		(property "Reference" "R190"
			(at 0 0 90)
			(layer "F.SilkS")
			(hide yes)
			(effects
				(font
					(size 1.27 1.27)
				)
			)
		)
		(property "Value" "4K7R2J-2-GP"
			(at 0.064008 -3.993896 90)
			(unlocked yes)
			(layer "F.Fab")
			(hide yes)
			(effects
				(font
					(size 1.016 1.016)
					(thickness 0.1524)
				)
			)
		)
		(property "Device Type" "R402H16"
			(at 0.064008 -5.517896 90)
			(unlocked yes)
			(layer "F.Fab")
			(hide yes)
			(effects
				(font
					(size 1.016 1.016)
					(thickness 0.1524)
				)
			)
		)
		(duplicate_pad_numbers_are_jumpers no)
		(fp_line
			(start 0.508 -0.9398)
			(end -0.508 -0.9398)
			(stroke
				(width 0.1524)
				(type default)
			)
			(layer "F.SilkS")
		)
		(fp_line
			(start -0.508 -0.9398)
			(end -0.508 0.9398)
			(stroke
				(width 0.1524)
				(type default)
			)
			(layer "F.SilkS")
		)
		(fp_rect
			(start -0.508 0.9398)
			(end 0.508 -0.9398)
			(stroke
				(width 0)
				(type default)
			)
			(fill no)
			(layer "F.CrtYd")
		)
		(fp_rect
			(start -0.508 0.9398)
			(end 0.508 -0.9398)
			(stroke
				(width 0)
				(type default)
			)
			(fill no)
			(layer "F.Fab")
		)
		(pad "1" smd custom
			(at 0 -0.4445 90)
			(size 0.1397 0.1397)
			(layers "F.Cu" "F.Mask" "F.Paste")
			(net "P12V_A")
			(options
				(clearance outline)
				(anchor circle)
			)
			(primitives
				(gr_poly
					(pts
						(arc
							(start -0.1778 -0.2794)
							(mid -0.249642 -0.249642)
							(end -0.2794 -0.1778)
						)
						(arc
							(start -0.2794 0.1778)
							(mid -0.249642 0.249642)
							(end -0.1778 0.2794)
						)
						(arc
							(start 0.1778 0.2794)
							(mid 0.249642 0.249642)
							(end 0.2794 0.1778)
						)
						(arc
							(start 0.2794 -0.1778)
							(mid 0.249642 -0.249642)
							(end 0.1778 -0.2794)
						)
					)
					(width 0)
					(fill yes)
				)
			)
		)
		(pad "2" smd custom
			(at 0 0.4445 90)
			(size 0.1397 0.1397)
			(layers "F.Cu" "F.Mask" "F.Paste")
			(net "SW_HDD_R2")
			(options
				(clearance outline)
				(anchor circle)
			)
			(primitives
				(gr_poly
					(pts
						(arc
							(start -0.1778 -0.2794)
							(mid -0.249642 -0.249642)
							(end -0.2794 -0.1778)
						)
						(arc
							(start -0.2794 0.1778)
							(mid -0.249642 0.249642)
							(end -0.1778 0.2794)
						)
						(arc
							(start 0.1778 0.2794)
							(mid 0.249642 0.249642)
							(end 0.2794 0.1778)
						)
						(arc
							(start 0.2794 -0.1778)
							(mid 0.249642 -0.249642)
							(end 0.1778 -0.2794)
						)
					)
					(width 0)
					(fill yes)
				)
			)
		)
	)
	(footprint ""
		(layer "F.Cu")
		(at 6.906006 -178.824636)
		(property "Reference" "Q223"
			(at 0 0 0)
			(layer "F.SilkS")
			(hide yes)
			(effects
				(font
					(size 1.27 1.27)
				)
			)
		)
		(property "Value" "2N7002K-2-GP"
			(at 0.127 -8.9662 0)
			(unlocked yes)
			(layer "F.Fab")
			(hide yes)
			(effects
				(font
					(size 1.016 1.016)
					(thickness 0.1524)
				)
			)
		)
		(property "Device Type" "SOT23DGS2D4H44"
			(at 0.127 -10.4902 0)
			(unlocked yes)
			(layer "F.Fab")
			(hide yes)
			(effects
				(font
					(size 1.016 1.016)
					(thickness 0.1524)
				)
			)
		)
		(duplicate_pad_numbers_are_jumpers no)
		(fp_line
			(start -1.651 -1.778)
			(end -1.651 1.778)
			(stroke
				(width 0.1524)
				(type default)
			)
			(layer "F.SilkS")
		)
		(fp_line
			(start -1.651 1.778)
			(end 1.651 1.778)
			(stroke
				(width 0.1524)
				(type default)
			)
			(layer "F.SilkS")
		)
		(fp_line
			(start 1.651 -1.778)
			(end -1.651 -1.778)
			(stroke
				(width 0.1524)
				(type default)
			)
			(layer "F.SilkS")
		)
		(fp_line
			(start 1.651 1.778)
			(end 1.651 -1.778)
			(stroke
				(width 0.1524)
				(type default)
			)
			(layer "F.SilkS")
		)
		(fp_poly
			(pts
				(xy -1.778 1.8796) (xy -1.778 -1.8796) (xy 1.778 -1.8796) (xy 1.778 1.8796)
			)
			(stroke
				(width 0)
				(type default)
			)
			(fill no)
			(layer "F.CrtYd")
		)
		(fp_poly
			(pts
				(xy -1.778 1.8796) (xy -1.778 -1.8796) (xy 1.778 -1.8796) (xy 1.778 1.8796)
			)
			(stroke
				(width 0)
				(type default)
			)
			(fill no)
			(layer "F.Fab")
		)
		(pad "D" smd custom
			(at 0 -0.9525)
			(size 0.1905 0.1905)
			(layers "F.Cu" "F.Mask" "F.Paste")
			(net "FLT_HDD0_N")
			(options
				(clearance outline)
				(anchor circle)
			)
			(primitives
				(gr_poly
					(pts
						(arc
							(start -0.1778 0.5715)
							(mid -0.321484 0.511984)
							(end -0.381 0.3683)
						)
						(arc
							(start -0.381 -0.3683)
							(mid -0.321484 -0.511984)
							(end -0.1778 -0.5715)
						)
						(arc
							(start 0.1778 -0.5715)
							(mid 0.321484 -0.511984)
							(end 0.381 -0.3683)
						)
						(arc
							(start 0.381 0.3683)
							(mid 0.321484 0.511984)
							(end 0.1778 0.5715)
						)
					)
					(width 0)
					(fill yes)
				)
			)
		)
		(pad "G" smd custom
			(at -0.98425 0.9525)
			(size 0.1905 0.1905)
			(layers "F.Cu" "F.Mask" "F.Paste")
			(net "DRIVE_A_0_FLT_LED")
			(options
				(clearance outline)
				(anchor circle)
			)
			(primitives
				(gr_poly
					(pts
						(arc
							(start -0.1778 0.5715)
							(mid -0.321484 0.511984)
							(end -0.381 0.3683)
						)
						(arc
							(start -0.381 -0.3683)
							(mid -0.321484 -0.511984)
							(end -0.1778 -0.5715)
						)
						(arc
							(start 0.1778 -0.5715)
							(mid 0.321484 -0.511984)
							(end 0.381 -0.3683)
						)
						(arc
							(start 0.381 0.3683)
							(mid 0.321484 0.511984)
							(end 0.1778 0.5715)
						)
					)
					(width 0)
					(fill yes)
				)
			)
		)
		(pad "S" smd custom
			(at 0.98425 0.9525)
			(size 0.1905 0.1905)
			(layers "F.Cu" "F.Mask" "F.Paste")
			(net "GND")
			(options
				(clearance outline)
				(anchor circle)
			)
			(primitives
				(gr_poly
					(pts
						(arc
							(start -0.1778 0.5715)
							(mid -0.321484 0.511984)
							(end -0.381 0.3683)
						)
						(arc
							(start -0.381 -0.3683)
							(mid -0.321484 -0.511984)
							(end -0.1778 -0.5715)
						)
						(arc
							(start 0.1778 -0.5715)
							(mid 0.321484 -0.511984)
							(end 0.381 -0.3683)
						)
						(arc
							(start 0.381 0.3683)
							(mid 0.321484 0.511984)
							(end 0.1778 0.5715)
						)
					)
					(width 0)
					(fill yes)
				)
			)
		)
	)
	(footprint ""
		(layer "F.Cu")
		(at 20.430998 -163.554918 180)
		(property "Reference" "Q73"
			(at 0 0 180)
			(layer "F.SilkS")
			(hide yes)
			(effects
				(font
					(size 1.27 1.27)
				)
			)
		)
		(property "Value" "2N7002KDW-GP"
			(at -2.3622 -8.2042 180)
			(unlocked yes)
			(layer "F.Fab")
			(hide yes)
			(effects
				(font
					(size 1.016 1.016)
					(thickness 0.1524)
				)
			)
		)
		(property "Device Type" "SOT-363H44"
			(at -2.3622 -10.1092 180)
			(unlocked yes)
			(layer "F.Fab")
			(hide yes)
			(effects
				(font
					(size 1.016 1.016)
					(thickness 0.1524)
				)
			)
		)
		(duplicate_pad_numbers_are_jumpers no)
		(fp_line
			(start 1.4478 1.7018)
			(end 1.4478 -1.7018)
			(stroke
				(width 0.1524)
				(type default)
			)
			(layer "F.SilkS")
		)
		(fp_line
			(start 1.4478 -1.7018)
			(end -1.4478 -1.7018)
			(stroke
				(width 0.1524)
				(type default)
			)
			(layer "F.SilkS")
		)
		(fp_line
			(start -1.27 1.524)
			(end -1.27 0.6604)
			(stroke
				(width 0.4826)
				(type default)
			)
			(layer "F.SilkS")
		)
		(fp_line
			(start -1.4478 1.7018)
			(end 1.4478 1.7018)
			(stroke
				(width 0.1524)
				(type default)
			)
			(layer "F.SilkS")
		)
		(fp_line
			(start -1.4478 -1.7018)
			(end -1.4478 1.7018)
			(stroke
				(width 0.1524)
				(type default)
			)
			(layer "F.SilkS")
		)
		(fp_poly
			(pts
				(xy -1.524 -1.778) (xy 1.524 -1.778) (xy 1.524 1.778) (xy -1.524 1.778)
			)
			(stroke
				(width 0)
				(type default)
			)
			(fill no)
			(layer "F.CrtYd")
		)
		(fp_poly
			(pts
				(xy -1.524 -1.778) (xy 1.524 -1.778) (xy 1.524 1.778) (xy -1.524 1.778)
			)
			(stroke
				(width 0)
				(type default)
			)
			(fill no)
			(layer "F.Fab")
		)
		(pad "1" smd rect
			(at -0.65024 0.9398 180)
			(size 0.4064 1.016)
			(layers "F.Cu" "F.Mask" "F.Paste")
			(net "GND")
		)
		(pad "2" smd rect
			(at 0 0.9398 180)
			(size 0.4064 1.016)
			(layers "F.Cu" "F.Mask" "F.Paste")
			(net "SW_PWR_R_HDD12")
		)
		(pad "3" smd rect
			(at 0.65024 0.9398 180)
			(size 0.4064 1.016)
			(layers "F.Cu" "F.Mask" "F.Paste")
			(net "SW_HDD_P12")
		)
		(pad "4" smd rect
			(at 0.65024 -0.9398 180)
			(size 0.4064 1.016)
			(layers "F.Cu" "F.Mask" "F.Paste")
			(net "GND")
		)
		(pad "5" smd rect
			(at 0 -0.9398 180)
			(size 0.4064 1.016)
			(layers "F.Cu" "F.Mask" "F.Paste")
			(net "SW_HDD_G12")
		)
		(pad "6" smd rect
			(at -0.65024 -0.9398 180)
			(size 0.4064 1.016)
			(layers "F.Cu" "F.Mask" "F.Paste")
			(net "SW_HDD_R12")
		)
	)
	(footprint ""
		(layer "F.Cu")
		(at 361.6198 -139.5984 90)
		(property "Reference" "R1105"
			(at 0 0 90)
			(layer "F.SilkS")
			(hide yes)
			(effects
				(font
					(size 1.27 1.27)
				)
			)
		)
		(property "Value" "10R2F-L-GP"
			(at 0.064008 -3.993896 90)
			(unlocked yes)
			(layer "F.Fab")
			(hide yes)
			(effects
				(font
					(size 1.016 1.016)
					(thickness 0.1524)
				)
			)
		)
		(property "Device Type" "R402H14"
			(at 0.064008 -5.517896 90)
			(unlocked yes)
			(layer "F.Fab")
			(hide yes)
			(effects
				(font
					(size 1.016 1.016)
					(thickness 0.1524)
				)
			)
		)
		(duplicate_pad_numbers_are_jumpers no)
		(fp_line
			(start 0.508 -0.9398)
			(end -0.508 -0.9398)
			(stroke
				(width 0.1524)
				(type default)
			)
			(layer "F.SilkS")
		)
		(fp_line
			(start -0.508 -0.9398)
			(end -0.508 0.9398)
			(stroke
				(width 0.1524)
				(type default)
			)
			(layer "F.SilkS")
		)
		(fp_rect
			(start -0.508 0.9398)
			(end 0.508 -0.9398)
			(stroke
				(width 0)
				(type default)
			)
			(fill no)
			(layer "F.CrtYd")
		)
		(fp_rect
			(start -0.508 0.9398)
			(end 0.508 -0.9398)
			(stroke
				(width 0)
				(type default)
			)
			(fill no)
			(layer "F.Fab")
		)
		(pad "1" smd custom
			(at 0 -0.4445 90)
			(size 0.1397 0.1397)
			(layers "F.Cu" "F.Mask" "F.Paste")
			(net "MB1_CM_SENSE_R1_P")
			(options
				(clearance outline)
				(anchor circle)
			)
			(primitives
				(gr_poly
					(pts
						(arc
							(start -0.1778 -0.2794)
							(mid -0.249642 -0.249642)
							(end -0.2794 -0.1778)
						)
						(arc
							(start -0.2794 0.1778)
							(mid -0.249642 0.249642)
							(end -0.1778 0.2794)
						)
						(arc
							(start 0.1778 0.2794)
							(mid 0.249642 0.249642)
							(end 0.2794 0.1778)
						)
						(arc
							(start 0.2794 -0.1778)
							(mid 0.249642 -0.249642)
							(end 0.1778 -0.2794)
						)
					)
					(width 0)
					(fill yes)
				)
			)
		)
		(pad "2" smd custom
			(at 0 0.4445 90)
			(size 0.1397 0.1397)
			(layers "F.Cu" "F.Mask" "F.Paste")
			(net "MB1_HS_SENSE_P")
			(options
				(clearance outline)
				(anchor circle)
			)
			(primitives
				(gr_poly
					(pts
						(arc
							(start -0.1778 -0.2794)
							(mid -0.249642 -0.249642)
							(end -0.2794 -0.1778)
						)
						(arc
							(start -0.2794 0.1778)
							(mid -0.249642 0.249642)
							(end -0.1778 0.2794)
						)
						(arc
							(start 0.1778 0.2794)
							(mid 0.249642 0.249642)
							(end 0.2794 0.1778)
						)
						(arc
							(start 0.2794 -0.1778)
							(mid 0.249642 -0.249642)
							(end 0.1778 -0.2794)
						)
					)
					(width 0)
					(fill yes)
				)
			)
		)
	)
)
